FILE_TYPE = MACRO_DRAWING;
SET COLOR_WIRE YELLOW;
SET COLOR_PROP ORANGE;
SET COLOR_DOT WHITE;
SET COLOR_ARC YELLOW;
SET COLOR_BODY GREEN;
SET COLOR_NOTE PURPLE;
SET PROP_DISPLAY VALUE;
SET PAGE_NUMBER P7;
FORCEADD QUANTA_TITLE_BLOCK_C..1
(6225 -1275);
FORCEPROP 1 LAST CUSTOM_TXT_CDS <NAME_2>
J 0
(3050 -1225);
FORCEPROP 1 LAST CUSTOM_TXT_CDS <NAME_1>
J 0
(3050 -1100);
FORCEPROP 1 LAST CUSTOM_TXT_CDS <Q_NUMBER>
J 0
(4822 -1172);
DISPLAY 1.212766 (4822 -1172);
FORCEPROP 1 LAST CUSTOM_TXT_CDS <Q_PROJ>
J 0
(3843 -1173);
DISPLAY 1.212766 (3843 -1173);
FORCEPROP 1 LAST CUSTOM_TXT_CDS <Q_REV>
J 0
(6041 -1172);
DISPLAY 1.212766 (6041 -1172);
FORCEPROP 1 LAST CUSTOM_TXT_CDS <CON_LAST_MODIFIED>
J 0
(4340 -1260);
DISPLAY 0.978723 (4340 -1260);
FORCEPROP 1 LAST CUSTOM_TXT_CDS <CON_PAGE_NUM> OF <CON_TOTAL_PAGES>
J 0
(5779 -1257);
DISPLAY 0.978723 (5779 -1257);
FORCEPROP 1 LAST Q_TITLE BLOCK DIAGRAM - VR
J 0
(-3141 -1249);
DISPLAY 2.446809 (-3141 -1249);
PAINT GREEN (-3141 -1249);
FORCEPROP 1 LAST Q_DEPT 
J 1
(2462 -1226);
DISPLAY 1.957447 (2462 -1226);
PAINT GREEN (2462 -1226);
FORCEPROP 2 LAST PAGE_BORDER TRUE
J 0
(-1665 3975);
DISPLAY 0.638298 (-1665 3975);
PAINT PINK (-1665 3975);
DISPLAY INVISIBLE (-1665 3975);
FORCEPROP 1 LAST COMMENT_BODY TRUE
J 0
(6237 -1288);
DISPLAY 0.978723 (6237 -1288);
PAINT GREEN (6237 -1288);
DISPLAY INVISIBLE (6237 -1288);
FORCEPROP 1 LAST CDS_LMAN_SYM_OUTLINE -9475,6775,100,-125
J 0
(6225 -1275);
DISPLAY 0.468085 (6225 -1275);
PAINT GREEN (6225 -1275);
DISPLAY INVISIBLE (6225 -1275);
FORCEPROP 2 LAST CDS_LIB pure_quanta
J 0
(6225 -1275);
PAINT MONO (6225 -1275);
DISPLAY INVISIBLE (6225 -1275);
FORCEPROP 2 LAST CDS_XR_PAGE_TITLE CR-7 : @S9S_MB_2U_LIB.S9S_MB_2U(SCH_1):PAGE7
J 0
(-1665 3975);
DISPLAY 0.638298 (-1665 3975);
PAINT PINK (-1665 3975);
DISPLAY INVISIBLE (-1665 3975);
FORCEPROP 2 LAST CUSTOM_TXT_CDS <XR_PAGE_TITLE>
J 0
(-1665 3975);
DISPLAY 0.638298 (-1665 3975);
PAINT PINK (-1665 3975);
DISPLAY INVISIBLE (-1665 3975);
FORCEPROP 0 LAST CDS_CON_LAST_MODIFIED Thu Aug 24 16:11:59 2023
J 0
(4340 -1260);
PAINT MONO (4340 -1260);
DISPLAY INVISIBLE (4340 -1260);
FORCENOTE
$CDS_IMAGE|F0T_diagram_MB_20220309_rev1-PWR.jpg|5617|6343
(1500 2200) 0;
DISPLAY LEFT (1500 2200);
QUIT
